# BASEBOARD_FAB2 (Tioga Pass) — schematic netlist excerpt (pin names and nets, part order shuffled) for the footprints in the layout excerpt that follows; sources: Cadence DE-HDL packaged netlist, KiCad conversion of Wiwynn_Tioga_Pass_MB.brd

C2N19  CAP_A  1.0UF 6.3V 10% X6S  pkg 0402V  page 130 : A = P3V3_STBY ; B = GND
C6U2  CAP  47UF 4V 20% X6S  pkg 0805  page 233 : A = PVPP_GHJ ; B = GND
C5P5  CAP  100UF 4V 20% X5R  pkg 0805  page 220 : A = PVDDQ_DEF ; B = GND

(kicad_pcb
	(version 20260206)
	(generator "pcbnew")
	(generator_version "10.0")
	(general
		(thickness 1.6)
		(legacy_teardrops no)
	)
	(paper "A4")
	(title_block
		(title "Wiwynn_Tioga_Pass_MB.brd")
		(comment 1 "Tioga Pass / footprints 3249-3251 of 4770")
	)
	(layers
		(0 "F.Cu" signal "TOP")
		(4 "In1.Cu" signal "L2GND")
		(6 "In2.Cu" signal "L3")
		(8 "In3.Cu" signal "L4GND")
		(10 "In4.Cu" signal "L5")
		(12 "In5.Cu" signal "L6GND")
		(14 "In6.Cu" signal "L7VCC")
		(16 "In7.Cu" signal "L8VCC")
		(18 "In8.Cu" signal "L9GND")
		(20 "In9.Cu" signal "L10")
		(22 "In10.Cu" signal "L11GND")
		(24 "In11.Cu" signal "L12")
		(26 "In12.Cu" signal "L13GND")
		(2 "B.Cu" signal "BOTTOM")
		(9 "F.Adhes" user "F.Adhesive")
		(11 "B.Adhes" user "B.Adhesive")
		(13 "F.Paste" user "Package Geometry/Pastemask Top")
		(15 "B.Paste" user "Package Geometry/Pastemask Bottom")
		(5 "F.SilkS" user "Ref Des/Silkscreen Top")
		(7 "B.SilkS" user "Ref Des/Silkscreen Bottom")
		(1 "F.Mask" user "Board Geometry/Soldermask Top")
		(3 "B.Mask" user "Board Geometry/Soldermask Bottom")
		(17 "Dwgs.User" user "User.Drawings")
		(19 "Cmts.User" user "User.Comments")
		(21 "Eco1.User" user "User.Eco1")
		(23 "Eco2.User" user "User.Eco2")
		(25 "Edge.Cuts" user "Board Geometry/Outline")
		(27 "Margin" user)
		(31 "F.CrtYd" user "Package Geometry/Place Bound Top")
		(29 "B.CrtYd" user "Package Geometry/Place Bound Bottom")
		(35 "F.Fab" user "Ref Des/Assembly Top")
		(33 "B.Fab" user "Ref Des/Assembly Bottom")
	)
	(footprint ""
		(layer "B.Cu")
		(at 271.223486 -85.06714)
		(property "Reference" "C5P5"
			(at 0 0 0)
			(layer "B.SilkS")
			(hide yes)
			(effects
				(font
					(size 1.27 1.27)
				)
				(justify mirror)
			)
		)
		(property "Value" ""
			(at 0 0 0)
			(layer "B.Fab")
			(effects
				(font
					(size 1.27 1.27)
				)
				(justify mirror)
			)
		)
		(duplicate_pad_numbers_are_jumpers no)
		(fp_poly
			(pts
				(xy 0.7239 -0.2159) (xy -0.7239 -0.2159) (xy -0.7239 1.9939) (xy 0.7239 1.9939)
			)
			(stroke
				(width 0)
				(type default)
			)
			(fill no)
			(layer "B.CrtYd")
		)
		(fp_line
			(start -0.7239 -0.2159)
			(end 0.7239 -0.2159)
			(stroke
				(width 0.1)
				(type default)
			)
			(layer "B.Fab")
		)
		(fp_line
			(start -0.7239 1.9939)
			(end -0.7239 -0.2159)
			(stroke
				(width 0.1)
				(type default)
			)
			(layer "B.Fab")
		)
		(fp_line
			(start 0.7239 -0.2159)
			(end 0.7239 1.9939)
			(stroke
				(width 0.1)
				(type default)
			)
			(layer "B.Fab")
		)
		(fp_line
			(start 0.7239 1.9939)
			(end -0.7239 1.9939)
			(stroke
				(width 0.1)
				(type default)
			)
			(layer "B.Fab")
		)
		(pad "1" smd rect
			(at 0 0 180)
			(size 1.27 1.016)
			(layers "B.Cu" "B.Mask" "B.Paste")
			(net "PVDDQ_DEF")
		)
		(pad "2" smd rect
			(at 0 1.778 180)
			(size 1.27 1.016)
			(layers "B.Cu" "B.Mask" "B.Paste")
			(net "GND")
		)
		(zone
			(layer "B.Cu")
			(hatch none 0.5)
			(connect_pads
				(clearance 0)
			)
			(min_thickness 0.25)
			(keepout
				(tracks not_allowed)
				(vias allowed)
				(pads allowed)
				(copperpour not_allowed)
				(footprints allowed)
			)
			(placement
				(enabled no)
				(sheetname "")
			)
			(fill
				(thermal_gap 0.5)
				(thermal_bridge_width 0.5)
				(island_removal_mode 0)
			)
			(polygon
				(pts
					(xy 271.858486 -84.55914) (xy 270.588486 -84.55914) (xy 270.588486 -83.79714) (xy 271.858486 -83.79714)
				)
			)
		)
	)
	(footprint ""
		(layer "B.Cu")
		(at 392.6586 -104.6226 135)
		(property "Reference" "C2N19"
			(at 0 0 135)
			(layer "B.SilkS")
			(hide yes)
			(effects
				(font
					(size 1.27 1.27)
				)
				(justify mirror)
			)
		)
		(property "Value" ""
			(at 0 0 135)
			(layer "B.Fab")
			(effects
				(font
					(size 1.27 1.27)
				)
				(justify mirror)
			)
		)
		(duplicate_pad_numbers_are_jumpers no)
		(fp_poly
			(pts
				(xy -0.279514 0.91437) (xy -0.279514 -0.11433) (xy 0.279286 -0.114331) (xy 0.279286 0.91437)
			)
			(stroke
				(width 0)
				(type default)
			)
			(fill no)
			(layer "B.CrtYd")
		)
		(fp_line
			(start 0.279466 -0.114229)
			(end -0.279466 -0.114229)
			(stroke
				(width 0.1)
				(type default)
			)
			(layer "B.Fab")
		)
		(fp_line
			(start -0.279466 -0.114229)
			(end -0.279286 0.91437)
			(stroke
				(width 0.1)
				(type default)
			)
			(layer "B.Fab")
		)
		(fp_line
			(start 0.279286 0.91437)
			(end 0.279466 -0.114229)
			(stroke
				(width 0.1)
				(type default)
			)
			(layer "B.Fab")
		)
		(fp_line
			(start -0.279286 0.91437)
			(end 0.279286 0.91437)
			(stroke
				(width 0.1)
				(type default)
			)
			(layer "B.Fab")
		)
		(pad "1" smd custom
			(at 0 0 45)
			(size 0.10414 0.10414)
			(layers "B.Cu" "B.Mask" "B.Paste")
			(net "P3V3_STBY")
			(options
				(clearance outline)
				(anchor circle)
			)
			(primitives
				(gr_poly
					(pts
						(xy -0.20828 -0.08636) (xy -0.20828 0.08636) (xy -0.08636 0.20828) (xy 0.086614 0.20828) (xy 0.20828 0.086614)
						(xy 0.20828 -0.08636) (xy 0.08636 -0.20828) (xy -0.08636 -0.20828)
					)
					(width 0)
					(fill yes)
				)
			)
		)
		(pad "2" smd custom
			(at 0 0.8001 45)
			(size 0.10414 0.10414)
			(layers "B.Cu" "B.Mask" "B.Paste")
			(net "GND")
			(options
				(clearance outline)
				(anchor circle)
			)
			(primitives
				(gr_poly
					(pts
						(xy -0.20828 -0.08636) (xy -0.20828 0.08636) (xy -0.08636 0.20828) (xy 0.086614 0.20828) (xy 0.20828 0.086614)
						(xy 0.20828 -0.08636) (xy 0.08636 -0.20828) (xy -0.08636 -0.20828)
					)
					(width 0)
					(fill yes)
				)
			)
		)
		(zone
			(layer "B.Cu")
			(hatch none 0.5)
			(connect_pads
				(clearance 0)
			)
			(min_thickness 0.25)
			(keepout
				(tracks allowed)
				(vias not_allowed)
				(pads allowed)
				(copperpour not_allowed)
				(footprints allowed)
			)
			(placement
				(enabled no)
				(sheetname "")
			)
			(fill
				(thermal_gap 0.5)
				(thermal_bridge_width 0.5)
				(island_removal_mode 0)
			)
			(polygon
				(pts
					(xy 392.744706 -104.832658) (xy 393.0142 -105.102152) (xy 393.138152 -104.9782) (xy 392.868912 -104.708706)
				)
			)
		)
		(zone
			(layer "B.Cu")
			(hatch none 0.5)
			(connect_pads
				(clearance 0)
			)
			(min_thickness 0.25)
			(keepout
				(tracks not_allowed)
				(vias allowed)
				(pads allowed)
				(copperpour not_allowed)
				(footprints allowed)
			)
			(placement
				(enabled no)
				(sheetname "")
			)
			(fill
				(thermal_gap 0.5)
				(thermal_bridge_width 0.5)
				(island_removal_mode 0)
			)
			(polygon
				(pts
					(xy 392.744706 -104.832658) (xy 393.0142 -105.102152) (xy 393.138152 -104.9782) (xy 392.868912 -104.708706)
				)
			)
		)
	)
	(footprint ""
		(layer "B.Cu")
		(at 167.005 -15.24 90)
		(property "Reference" "C6U2"
			(at 0 0 90)
			(layer "B.SilkS")
			(hide yes)
			(effects
				(font
					(size 1.27 1.27)
				)
				(justify mirror)
			)
		)
		(property "Value" ""
			(at 0 0 90)
			(layer "B.Fab")
			(effects
				(font
					(size 1.27 1.27)
				)
				(justify mirror)
			)
		)
		(duplicate_pad_numbers_are_jumpers no)
		(fp_rect
			(start -0.7239 -0.2159)
			(end 0.7239 1.9939)
			(stroke
				(width 0)
				(type default)
			)
			(fill no)
			(layer "B.CrtYd")
		)
		(fp_line
			(start 0.7239 -0.2159)
			(end 0.7239 1.9939)
			(stroke
				(width 0.1)
				(type default)
			)
			(layer "B.Fab")
		)
		(fp_line
			(start -0.7239 -0.2159)
			(end 0.7239 -0.2159)
			(stroke
				(width 0.1)
				(type default)
			)
			(layer "B.Fab")
		)
		(fp_line
			(start 0.7239 1.9939)
			(end -0.7239 1.9939)
			(stroke
				(width 0.1)
				(type default)
			)
			(layer "B.Fab")
		)
		(fp_line
			(start -0.7239 1.9939)
			(end -0.7239 -0.2159)
			(stroke
				(width 0.1)
				(type default)
			)
			(layer "B.Fab")
		)
		(pad "1" smd rect
			(at 0 0 270)
			(size 1.27 1.016)
			(layers "B.Cu" "B.Mask" "B.Paste")
			(net "PVPP_GHJ")
		)
		(pad "2" smd rect
			(at 0 1.778 270)
			(size 1.27 1.016)
			(layers "B.Cu" "B.Mask" "B.Paste")
			(net "GND")
		)
		(zone
			(layer "B.Cu")
			(hatch none 0.5)
			(connect_pads
				(clearance 0)
			)
			(min_thickness 0.25)
			(keepout
				(tracks not_allowed)
				(vias allowed)
				(pads allowed)
				(copperpour not_allowed)
				(footprints allowed)
			)
			(placement
				(enabled no)
				(sheetname "")
			)
			(fill
				(thermal_gap 0.5)
				(thermal_bridge_width 0.5)
				(island_removal_mode 0)
			)
			(polygon
				(pts
					(xy 167.513 -14.605) (xy 168.275 -14.605) (xy 168.275 -15.875) (xy 167.513 -15.875)
				)
			)
		)
	)
)
